(kicad_pcb
	(version 20260206)
	(generator "pcbnew")
	(generator_version "10.0")
	(general
		(thickness 1.6)
		(legacy_teardrops no)
	)
	(paper "A4")
	(title_block
		(title "04192023_DAF0TMB3IC0_F0TG_MB_C_brd_V02_OCP.brd")
		(comment 1 "Grand Teton / footprints 3280-3285 of 8354")
	)
	(layers
		(0 "F.Cu" signal "TOP")
		(4 "In1.Cu" signal "GND")
		(6 "In2.Cu" signal "IN1")
		(8 "In3.Cu" signal "GND1")
		(10 "In4.Cu" signal "IN2")
		(12 "In5.Cu" signal "GND2")
		(14 "In6.Cu" signal "IN3")
		(16 "In7.Cu" signal "GND3")
		(18 "In8.Cu" signal "VCC")
		(20 "In9.Cu" signal "VCC1")
		(22 "In10.Cu" signal "GND4")
		(24 "In11.Cu" signal "IN4")
		(26 "In12.Cu" signal "GND5")
		(28 "In13.Cu" signal "IN5")
		(30 "In14.Cu" signal "GND6")
		(32 "In15.Cu" signal "IN6")
		(34 "In16.Cu" signal "GND7")
		(2 "B.Cu" signal "BOTTOM")
		(9 "F.Adhes" user "F.Adhesive")
		(11 "B.Adhes" user "B.Adhesive")
		(13 "F.Paste" user "Package Geometry/Pastemask Top")
		(15 "B.Paste" user "Package Geometry/Pastemask Bottom")
		(5 "F.SilkS" user "Ref Des/Silkscreen Top")
		(7 "B.SilkS" user "Ref Des/Silkscreen Bottom")
		(1 "F.Mask" user "Board Geometry/Soldermask Top")
		(3 "B.Mask" user "Board Geometry/Soldermask Bottom")
		(17 "Dwgs.User" user "User.Drawings")
		(19 "Cmts.User" user "User.Comments")
		(21 "Eco1.User" user "User.Eco1")
		(23 "Eco2.User" user "User.Eco2")
		(25 "Edge.Cuts" user "Board Geometry/Outline")
		(27 "Margin" user)
		(31 "F.CrtYd" user "Package Geometry/Place Bound Top")
		(29 "B.CrtYd" user "Package Geometry/Place Bound Bottom")
		(35 "F.Fab" user "Ref Des/Assembly Top")
		(33 "B.Fab" user "Ref Des/Assembly Bottom")
	)
	(footprint ""
		(layer "F.Cu")
		(at 28.5369 -421.069008 180)
		(property "Reference" "C1870"
			(at 0 0 180)
			(layer "F.SilkS")
			(hide yes)
			(effects
				(font
					(size 1.27 1.27)
				)
			)
		)
		(property "Value" ""
			(at 0 0 180)
			(layer "F.Fab")
			(effects
				(font
					(size 1.27 1.27)
				)
			)
		)
		(duplicate_pad_numbers_are_jumpers no)
		(fp_line
			(start 0.7874 -0.4064)
			(end 0.7874 0.215392)
			(stroke
				(width 0.1524)
				(type default)
			)
			(layer "F.SilkS")
		)
		(fp_line
			(start -0.3429 0.4064)
			(end -0.7874 0.4064)
			(stroke
				(width 0.1524)
				(type default)
			)
			(layer "F.SilkS")
		)
		(fp_line
			(start -0.7874 -0.4064)
			(end 0.7874 -0.4064)
			(stroke
				(width 0.1524)
				(type default)
			)
			(layer "F.SilkS")
		)
		(fp_line
			(start 0.6858 0.3048)
			(end 0.1016 0.3048)
			(stroke
				(width 0.1)
				(type default)
			)
			(layer "F.Fab")
		)
		(fp_line
			(start 0.6858 -0.3048)
			(end 0.6858 0.3048)
			(stroke
				(width 0.1)
				(type default)
			)
			(layer "F.Fab")
		)
		(fp_line
			(start 0.1016 0.3048)
			(end 0.1016 0.2794)
			(stroke
				(width 0.1)
				(type default)
			)
			(layer "F.Fab")
		)
		(fp_line
			(start 0.1016 0.2794)
			(end -0.1016 0.2794)
			(stroke
				(width 0.1)
				(type default)
			)
			(layer "F.Fab")
		)
		(fp_line
			(start 0.1016 -0.2794)
			(end 0.1016 -0.3048)
			(stroke
				(width 0.1)
				(type default)
			)
			(layer "F.Fab")
		)
		(fp_line
			(start 0.1016 -0.3048)
			(end 0.6858 -0.3048)
			(stroke
				(width 0.1)
				(type default)
			)
			(layer "F.Fab")
		)
		(fp_line
			(start -0.1016 0.3048)
			(end -0.6858 0.3048)
			(stroke
				(width 0.1)
				(type default)
			)
			(layer "F.Fab")
		)
		(fp_line
			(start -0.1016 0.2794)
			(end -0.1016 0.3048)
			(stroke
				(width 0.1)
				(type default)
			)
			(layer "F.Fab")
		)
		(fp_line
			(start -0.1016 -0.2794)
			(end 0.1016 -0.2794)
			(stroke
				(width 0.1)
				(type default)
			)
			(layer "F.Fab")
		)
		(fp_line
			(start -0.1016 -0.3048)
			(end -0.1016 -0.2794)
			(stroke
				(width 0.1)
				(type default)
			)
			(layer "F.Fab")
		)
		(fp_line
			(start -0.6858 0.3048)
			(end -0.6858 -0.3048)
			(stroke
				(width 0.1)
				(type default)
			)
			(layer "F.Fab")
		)
		(fp_line
			(start -0.6858 -0.3048)
			(end -0.1016 -0.3048)
			(stroke
				(width 0.1)
				(type default)
			)
			(layer "F.Fab")
		)
		(pad "1" smd rect
			(at -0.40005 0)
			(size 0.4572 0.508)
			(layers "F.Cu" "F.Mask" "F.Paste")
			(net "P2E_MB_BMC_TX_BUF_DP<0>")
		)
		(pad "2" smd rect
			(at 0.40005 0)
			(size 0.4572 0.508)
			(layers "F.Cu" "F.Mask" "F.Paste")
			(net "P2E_MB_BMC_TX_BUF_C_DP<0>")
		)
	)
	(footprint ""
		(layer "F.Cu")
		(at 191.055498 -425.829476 -90)
		(property "Reference" "R2794"
			(at 0 0 270)
			(layer "F.SilkS")
			(hide yes)
			(effects
				(font
					(size 1.27 1.27)
				)
			)
		)
		(property "Value" ""
			(at 0 0 270)
			(layer "F.Fab")
			(effects
				(font
					(size 1.27 1.27)
				)
			)
		)
		(duplicate_pad_numbers_are_jumpers no)
		(fp_line
			(start -0.7874 0.4064)
			(end -0.7874 -0.4064)
			(stroke
				(width 0.1524)
				(type default)
			)
			(layer "F.SilkS")
		)
		(fp_line
			(start 0.7874 0.4064)
			(end -0.7874 0.4064)
			(stroke
				(width 0.1524)
				(type default)
			)
			(layer "F.SilkS")
		)
		(fp_line
			(start -0.7874 -0.4064)
			(end 0.7874 -0.4064)
			(stroke
				(width 0.1524)
				(type default)
			)
			(layer "F.SilkS")
		)
		(fp_line
			(start 0.7874 -0.4064)
			(end 0.7874 0.4064)
			(stroke
				(width 0.1524)
				(type default)
			)
			(layer "F.SilkS")
		)
		(fp_line
			(start -0.67945 0.3048)
			(end -0.67945 -0.305054)
			(stroke
				(width 0.1)
				(type default)
			)
			(layer "F.Fab")
		)
		(fp_line
			(start -0.12065 0.3048)
			(end -0.67945 0.3048)
			(stroke
				(width 0.1)
				(type default)
			)
			(layer "F.Fab")
		)
		(fp_line
			(start 0.120396 0.3048)
			(end 0.120396 0.2794)
			(stroke
				(width 0.1)
				(type default)
			)
			(layer "F.Fab")
		)
		(fp_line
			(start 0.67945 0.3048)
			(end 0.120396 0.3048)
			(stroke
				(width 0.1)
				(type default)
			)
			(layer "F.Fab")
		)
		(fp_line
			(start -0.12065 0.2794)
			(end -0.12065 0.3048)
			(stroke
				(width 0.1)
				(type default)
			)
			(layer "F.Fab")
		)
		(fp_line
			(start 0.120396 0.2794)
			(end -0.12065 0.2794)
			(stroke
				(width 0.1)
				(type default)
			)
			(layer "F.Fab")
		)
		(fp_line
			(start -0.12065 -0.2794)
			(end 0.12065 -0.2794)
			(stroke
				(width 0.1)
				(type default)
			)
			(layer "F.Fab")
		)
		(fp_line
			(start 0.12065 -0.2794)
			(end 0.12065 -0.3048)
			(stroke
				(width 0.1)
				(type default)
			)
			(layer "F.Fab")
		)
		(fp_line
			(start 0.12065 -0.3048)
			(end 0.67945 -0.3048)
			(stroke
				(width 0.1)
				(type default)
			)
			(layer "F.Fab")
		)
		(fp_line
			(start 0.67945 -0.3048)
			(end 0.67945 0.3048)
			(stroke
				(width 0.1)
				(type default)
			)
			(layer "F.Fab")
		)
		(fp_line
			(start -0.67945 -0.305054)
			(end -0.12065 -0.305054)
			(stroke
				(width 0.1)
				(type default)
			)
			(layer "F.Fab")
		)
		(fp_line
			(start -0.12065 -0.305054)
			(end -0.12065 -0.2794)
			(stroke
				(width 0.1)
				(type default)
			)
			(layer "F.Fab")
		)
		(pad "1" smd circle
			(at -0.40005 0 270)
			(size 0 0)
			(layers "F.Cu" "F.Mask" "F.Paste")
			(net "P3V3_AUX")
		)
		(pad "2" smd circle
			(at 0.40005 0 270)
			(size 0 0)
			(layers "F.Cu" "F.Mask" "F.Paste")
			(net "FM_PDB_BUF_EN_R1")
		)
	)
	(footprint ""
		(layer "F.Cu")
		(at 146.214846 -396.491206 -90)
		(property "Reference" "R871"
			(at 0 0 270)
			(layer "F.SilkS")
			(hide yes)
			(effects
				(font
					(size 1.27 1.27)
				)
			)
		)
		(property "Value" ""
			(at 0 0 270)
			(layer "F.Fab")
			(effects
				(font
					(size 1.27 1.27)
				)
			)
		)
		(duplicate_pad_numbers_are_jumpers no)
		(fp_line
			(start -0.32512 0.175006)
			(end -0.32512 -0.175006)
			(stroke
				(width 0.1)
				(type default)
			)
			(layer "F.Fab")
		)
		(fp_line
			(start 0.32512 0.175006)
			(end -0.32512 0.175006)
			(stroke
				(width 0.1)
				(type default)
			)
			(layer "F.Fab")
		)
		(fp_line
			(start -0.32512 -0.175006)
			(end 0.32512 -0.175006)
			(stroke
				(width 0.1)
				(type default)
			)
			(layer "F.Fab")
		)
		(fp_line
			(start 0.32512 -0.175006)
			(end 0.32512 0.175006)
			(stroke
				(width 0.1)
				(type default)
			)
			(layer "F.Fab")
		)
		(pad "1" smd rect
			(at -0.2667 0 270)
			(size 0.3048 0.381)
			(layers "F.Cu" "F.Mask" "F.Paste")
			(net "P1V8_CPU1_RT_1D")
		)
		(pad "2" smd rect
			(at 0.2667 0 90)
			(size 0.3048 0.381)
			(layers "F.Cu" "F.Mask" "F.Paste")
			(net "JTAG_TEST_MODE_RT_CPU1_P2")
		)
	)
	(footprint ""
		(layer "F.Cu")
		(at 389.462264 6.149848)
		(property "Reference" "J72"
			(at -4.619498 0.932434 90)
			(unlocked yes)
			(layer "F.SilkS")
			(effects
				(font
					(size 0.7874 0.5842)
					(thickness 0.1524)
				)
				(justify left)
			)
		)
		(property "Value" ""
			(at 0 0 0)
			(layer "F.Fab")
			(effects
				(font
					(size 1.27 1.27)
				)
			)
		)
		(duplicate_pad_numbers_are_jumpers no)
		(fp_line
			(start -1.2192 -2.06756)
			(end 1.2192 -2.06756)
			(stroke
				(width 0.1524)
				(type default)
			)
			(layer "F.SilkS")
		)
		(fp_line
			(start -1.2192 2.06756)
			(end -1.2192 -2.06756)
			(stroke
				(width 0.1524)
				(type default)
			)
			(layer "F.SilkS")
		)
		(fp_line
			(start 1.2192 -2.06756)
			(end 1.2192 2.06756)
			(stroke
				(width 0.1524)
				(type default)
			)
			(layer "F.SilkS")
		)
		(fp_line
			(start 1.2192 2.06756)
			(end -1.2192 2.06756)
			(stroke
				(width 0.1524)
				(type default)
			)
			(layer "F.SilkS")
		)
		(pad "" np_thru_hole circle
			(at -2.8829 -1.27 270)
			(size 1.0414 1.0414)
			(drill 1.0414)
			(layers "*.Cu" "*.Mask")
			(clearance 0.381)
			(thermal_gap 0.381)
		)
		(pad "" np_thru_hole circle
			(at -2.8829 1.27 270)
			(size 1.0414 1.0414)
			(drill 1.0414)
			(layers "*.Cu" "*.Mask")
			(clearance 0.381)
			(thermal_gap 0.381)
		)
		(pad "" np_thru_hole circle
			(at 3.4671 -1.27 270)
			(size 1.0414 1.0414)
			(drill 1.0414)
			(layers "*.Cu" "*.Mask")
			(clearance 0.381)
			(thermal_gap 0.381)
		)
		(pad "" np_thru_hole circle
			(at 3.4671 1.27 270)
			(size 1.0414 1.0414)
			(drill 1.0414)
			(layers "*.Cu" "*.Mask")
			(clearance 0.381)
			(thermal_gap 0.381)
		)
		(pad "1" smd rect
			(at 0.8255 -0.249936 270)
			(size 0.3048 0.508)
			(layers "F.Cu" "F.Mask" "F.Paste")
			(net "DELTA_L_85_5INCH_IN2_DN")
		)
		(pad "2" smd rect
			(at 0.8255 0.249936 270)
			(size 0.3048 0.508)
			(layers "F.Cu" "F.Mask" "F.Paste")
			(net "DELTA_L_85_5INCH_IN2_DP")
		)
		(pad "3" smd circle
			(at 0 0)
			(size 0 0)
			(layers "F.Cu" "F.Mask" "F.Paste")
			(net "DELTA_L_GND_1")
		)
		(zone
			(layer "F.Cu")
			(hatch none 0.5)
			(connect_pads
				(clearance 0)
			)
			(min_thickness 0.25)
			(keepout
				(tracks not_allowed)
				(vias allowed)
				(pads allowed)
				(copperpour not_allowed)
				(footprints allowed)
			)
			(placement
				(enabled no)
				(sheetname "")
			)
			(fill
				(thermal_gap 0.5)
				(thermal_bridge_width 0.5)
				(island_removal_mode 0)
			)
			(polygon
				(pts
					(xy 390.579864 5.601208) (xy 390.579864 5.696712) (xy 389.982964 5.696712) (xy 389.982964 6.103112)
					(xy 390.579864 6.103112) (xy 390.579864 6.196584) (xy 389.982964 6.196584) (xy 389.982964 6.602984)
					(xy 390.579864 6.602984) (xy 390.579864 6.698488) (xy 389.881364 6.698488) (xy 389.881364 5.601208)
				)
			)
		)
		(zone
			(layers "F.Cu" "B.Cu" "In1.Cu" "In2.Cu" "In3.Cu" "In4.Cu" "In5.Cu" "In6.Cu"
				"In7.Cu" "In8.Cu" "In9.Cu" "In10.Cu" "In11.Cu" "In12.Cu" "In13.Cu" "In14.Cu"
				"In15.Cu" "In16.Cu"
			)
			(hatch none 0.5)
			(connect_pads
				(clearance 0)
			)
			(min_thickness 0.25)
			(keepout
				(tracks not_allowed)
				(vias allowed)
				(pads allowed)
				(copperpour not_allowed)
				(footprints allowed)
			)
			(placement
				(enabled no)
				(sheetname "")
			)
			(fill
				(thermal_gap 0.5)
				(thermal_bridge_width 0.5)
				(island_removal_mode 0)
			)
			(polygon
				(pts
					(arc
						(start 387.506464 4.879848)
						(mid 385.652264 4.879848)
						(end 387.506464 4.879848)
					)
				)
			)
		)
		(zone
			(layers "F.Cu" "B.Cu" "In1.Cu" "In2.Cu" "In3.Cu" "In4.Cu" "In5.Cu" "In6.Cu"
				"In7.Cu" "In8.Cu" "In9.Cu" "In10.Cu" "In11.Cu" "In12.Cu" "In13.Cu" "In14.Cu"
				"In15.Cu" "In16.Cu"
			)
			(hatch none 0.5)
			(connect_pads
				(clearance 0)
			)
			(min_thickness 0.25)
			(keepout
				(tracks not_allowed)
				(vias allowed)
				(pads allowed)
				(copperpour not_allowed)
				(footprints allowed)
			)
			(placement
				(enabled no)
				(sheetname "")
			)
			(fill
				(thermal_gap 0.5)
				(thermal_bridge_width 0.5)
				(island_removal_mode 0)
			)
			(polygon
				(pts
					(arc
						(start 387.506464 7.419848)
						(mid 385.652264 7.419848)
						(end 387.506464 7.419848)
					)
				)
			)
		)
		(zone
			(layers "F.Cu" "B.Cu" "In1.Cu" "In2.Cu" "In3.Cu" "In4.Cu" "In5.Cu" "In6.Cu"
				"In7.Cu" "In8.Cu" "In9.Cu" "In10.Cu" "In11.Cu" "In12.Cu" "In13.Cu" "In14.Cu"
				"In15.Cu" "In16.Cu"
			)
			(hatch none 0.5)
			(connect_pads
				(clearance 0)
			)
			(min_thickness 0.25)
			(keepout
				(tracks not_allowed)
				(vias allowed)
				(pads allowed)
				(copperpour not_allowed)
				(footprints allowed)
			)
			(placement
				(enabled no)
				(sheetname "")
			)
			(fill
				(thermal_gap 0.5)
				(thermal_bridge_width 0.5)
				(island_removal_mode 0)
			)
			(polygon
				(pts
					(arc
						(start 393.856464 4.879848)
						(mid 392.002264 4.879848)
						(end 393.856464 4.879848)
					)
				)
			)
		)
		(zone
			(layers "F.Cu" "B.Cu" "In1.Cu" "In2.Cu" "In3.Cu" "In4.Cu" "In5.Cu" "In6.Cu"
				"In7.Cu" "In8.Cu" "In9.Cu" "In10.Cu" "In11.Cu" "In12.Cu" "In13.Cu" "In14.Cu"
				"In15.Cu" "In16.Cu"
			)
			(hatch none 0.5)
			(connect_pads
				(clearance 0)
			)
			(min_thickness 0.25)
			(keepout
				(tracks not_allowed)
				(vias allowed)
				(pads allowed)
				(copperpour not_allowed)
				(footprints allowed)
			)
			(placement
				(enabled no)
				(sheetname "")
			)
			(fill
				(thermal_gap 0.5)
				(thermal_bridge_width 0.5)
				(island_removal_mode 0)
			)
			(polygon
				(pts
					(arc
						(start 393.856464 7.419848)
						(mid 392.002264 7.419848)
						(end 393.856464 7.419848)
					)
				)
			)
		)
	)
	(footprint ""
		(layer "F.Cu")
		(at 308.757574 -22.185884 90)
		(property "Reference" "C62"
			(at 0 0 90)
			(layer "F.SilkS")
			(hide yes)
			(effects
				(font
					(size 1.27 1.27)
				)
			)
		)
		(property "Value" ""
			(at 0 0 90)
			(layer "F.Fab")
			(effects
				(font
					(size 1.27 1.27)
				)
			)
		)
		(duplicate_pad_numbers_are_jumpers no)
		(fp_line
			(start 0.7874 -0.4064)
			(end 0.7874 0.4064)
			(stroke
				(width 0.1524)
				(type default)
			)
			(layer "F.SilkS")
		)
		(fp_line
			(start -0.7874 -0.4064)
			(end 0.7874 -0.4064)
			(stroke
				(width 0.1524)
				(type default)
			)
			(layer "F.SilkS")
		)
		(fp_line
			(start 0.7874 0.4064)
			(end -0.7874 0.4064)
			(stroke
				(width 0.1524)
				(type default)
			)
			(layer "F.SilkS")
		)
		(fp_line
			(start -0.7874 0.4064)
			(end -0.7874 -0.4064)
			(stroke
				(width 0.1524)
				(type default)
			)
			(layer "F.SilkS")
		)
		(fp_line
			(start -0.12065 -0.305054)
			(end -0.12065 -0.2794)
			(stroke
				(width 0.1)
				(type default)
			)
			(layer "F.Fab")
		)
		(fp_line
			(start -0.67945 -0.305054)
			(end -0.12065 -0.305054)
			(stroke
				(width 0.1)
				(type default)
			)
			(layer "F.Fab")
		)
		(fp_line
			(start 0.67945 -0.3048)
			(end 0.67945 0.3048)
			(stroke
				(width 0.1)
				(type default)
			)
			(layer "F.Fab")
		)
		(fp_line
			(start 0.12065 -0.3048)
			(end 0.67945 -0.3048)
			(stroke
				(width 0.1)
				(type default)
			)
			(layer "F.Fab")
		)
		(fp_line
			(start 0.12065 -0.2794)
			(end 0.12065 -0.3048)
			(stroke
				(width 0.1)
				(type default)
			)
			(layer "F.Fab")
		)
		(fp_line
			(start -0.12065 -0.2794)
			(end 0.12065 -0.2794)
			(stroke
				(width 0.1)
				(type default)
			)
			(layer "F.Fab")
		)
		(fp_line
			(start 0.120396 0.2794)
			(end -0.12065 0.2794)
			(stroke
				(width 0.1)
				(type default)
			)
			(layer "F.Fab")
		)
		(fp_line
			(start -0.12065 0.2794)
			(end -0.12065 0.3048)
			(stroke
				(width 0.1)
				(type default)
			)
			(layer "F.Fab")
		)
		(fp_line
			(start 0.67945 0.3048)
			(end 0.120396 0.3048)
			(stroke
				(width 0.1)
				(type default)
			)
			(layer "F.Fab")
		)
		(fp_line
			(start 0.120396 0.3048)
			(end 0.120396 0.2794)
			(stroke
				(width 0.1)
				(type default)
			)
			(layer "F.Fab")
		)
		(fp_line
			(start -0.12065 0.3048)
			(end -0.67945 0.3048)
			(stroke
				(width 0.1)
				(type default)
			)
			(layer "F.Fab")
		)
		(fp_line
			(start -0.67945 0.3048)
			(end -0.67945 -0.305054)
			(stroke
				(width 0.1)
				(type default)
			)
			(layer "F.Fab")
		)
		(pad "1" smd circle
			(at -0.40005 0 90)
			(size 0 0)
			(layers "F.Cu" "F.Mask" "F.Paste")
			(net "UART_CPU0_SCM_LVC3_UART1_TX")
		)
		(pad "2" smd circle
			(at 0.40005 0 90)
			(size 0 0)
			(layers "F.Cu" "F.Mask" "F.Paste")
			(net "GND")
		)
	)
	(footprint ""
		(layer "F.Cu")
		(at 137.225786 -408.517344 -90)
		(property "Reference" "C6707"
			(at 0 0 270)
			(layer "F.SilkS")
			(hide yes)
			(effects
				(font
					(size 1.27 1.27)
				)
			)
		)
		(property "Value" ""
			(at 0 0 270)
			(layer "F.Fab")
			(effects
				(font
					(size 1.27 1.27)
				)
			)
		)
		(duplicate_pad_numbers_are_jumpers no)
		(fp_line
			(start -0.299974 0.150114)
			(end -0.299974 -0.150114)
			(stroke
				(width 0.1)
				(type default)
			)
			(layer "F.Fab")
		)
		(fp_line
			(start 0.299974 0.150114)
			(end -0.299974 0.150114)
			(stroke
				(width 0.1)
				(type default)
			)
			(layer "F.Fab")
		)
		(fp_line
			(start -0.299974 -0.150114)
			(end 0.299974 -0.150114)
			(stroke
				(width 0.1)
				(type default)
			)
			(layer "F.Fab")
		)
		(fp_line
			(start 0.299974 -0.150114)
			(end 0.299974 0.150114)
			(stroke
				(width 0.1)
				(type default)
			)
			(layer "F.Fab")
		)
		(pad "1" smd rect
			(at -0.2667 0 270)
			(size 0.3048 0.381)
			(layers "F.Cu" "F.Mask" "F.Paste")
			(net "P5E_CPU1_P2_TX_BUF_C_DP<7>")
		)
		(pad "2" smd rect
			(at 0.2667 0 270)
			(size 0.3048 0.381)
			(layers "F.Cu" "F.Mask" "F.Paste")
			(net "P5E_CPU1_P2_TX_BUF_DP<7>")
		)
	)
)
